FILE_TYPE = MULTI_PHYS_TABLE;

PART 'PCA9555APW'

{========================================================================================}
:VALUE        | PART_TYPE | MATERIAL | PART_NUMBER    = STANDARD    | LIFECYCLE      | PART_NUMBER   | JEDEC_TYPE  | DESCRIPTION                      | MANUFTR | MANUF_PN     | RD_CMPLS_LVL | CMPLS_LVL | FROM_PJ      | CLASS | DIP_SMD | DATA                 | EE_CHECK_LIST | FP_ECN | PSL | CREATOR | STATUS | MSD | ESD_CDM | ESD_HBM | ESD_MM | PIN_LENGTH_SHORT_PIN | PIN_LENGTH_LONG_PIN | CREATEDAY  ;
{========================================================================================}
 'PCA9555APW' | 'SMLF'    | 'IC'     | 'AL009555K07'(!) = ''               | ''               | 'AL009555K07' |'TSSOP24XB'| 'IC OTHER(24P)PCA9555APW(TSSOP)' | 'NXP'   | 'PCA9555APW' | 'EP(V1)'     | 'EP(V1)'  | 'IX5-BRYANT' | 'IC'  | ''      | 'NXP_PCA9555APW.pdf' | ''            | ''     | ''  | ''      | ''     | ''  | ''      | ''      | ''     | '0 MILS'             | '0 MILS'            | '20210721'
 'PCA9555APW' | 'SMLF'    | 'EMPTY'  | 'AL009555K07'(!) = ''               | ''               | 'AL009555K07' |'TSSOP24XB'| 'IC OTHER(24P)PCA9555APW(TSSOP)' | 'NXP'   | 'PCA9555APW' | 'EP(V1)'     | 'EP(V1)'  | 'IX5-BRYANT' | 'IC'  | ''      | 'NXP_PCA9555APW.pdf' | ''            | ''     | ''  | ''      | ''     | ''  | ''      | ''      | ''     | '0 MILS'             | '0 MILS'            | '20210721'

END_PART

END.

